(kicad_pcb
	(version 20240108)
	(generator "pcbnew")
	(generator_version "8.0")
	(general
		(thickness 1.6)
		(legacy_teardrops no)
	)
	(paper "A4")
	(title_block
		(title "Jetson Orin Baseboard OCuLink Expansion")
		(date "2025-03-18")
		(rev "1.1.0")
		(company "Antmicro Ltd")
		(comment 1 "www.antmicro.com")
		(comment 9 "footprints 104-107 of 119")
	)
	(layers
		(0 "F.Cu" signal)
		(1 "In1.Cu" signal)
		(2 "In2.Cu" signal)
		(31 "B.Cu" signal)
		(32 "B.Adhes" user "B.Adhesive")
		(33 "F.Adhes" user "F.Adhesive")
		(34 "B.Paste" user)
		(35 "F.Paste" user)
		(36 "B.SilkS" user "B.Silkscreen")
		(37 "F.SilkS" user "F.Silkscreen")
		(38 "B.Mask" user)
		(39 "F.Mask" user)
		(40 "Dwgs.User" user "User.Drawings")
		(41 "Cmts.User" user "User.Comments")
		(42 "Eco1.User" user "User.Eco1")
		(43 "Eco2.User" user "User.Eco2")
		(44 "Edge.Cuts" user)
		(45 "Margin" user)
		(46 "B.CrtYd" user "B.Courtyard")
		(47 "F.CrtYd" user "F.Courtyard")
		(48 "B.Fab" user)
		(49 "F.Fab" user)
	)
	(footprint "antmicro-footprints:C_0402_1005Metric"
		(layer "B.Cu")
		(at 119.775 125.795 90)
		(descr "Capacitor SMD 0402")
		(tags "capacitor SMD 0402")
		(property "Reference" "C26"
			(at 1.605 -0.355 90)
			(layer "B.SilkS")
			(effects
				(font
					(size 0.7 0.7)
					(thickness 0.15)
				)
				(justify right top mirror)
			)
		)
		(property "Value" "C_100n_0402"
			(at -1.022927 -2.155213 90)
			(layer "B.Fab")
			(effects
				(font
					(size 0.7 0.7)
					(thickness 0.15)
				)
				(justify right top mirror)
			)
		)
		(property "Footprint" "antmicro-footprints:C_0402_1005Metric"
			(at 0 0 90)
			(layer "B.Fab")
			(hide yes)
			(effects
				(font
					(size 1.27 1.27)
					(thickness 0.15)
				)
				(justify mirror)
			)
		)
		(property "Datasheet" "https://www.murata.com/products/productdetail?partno=GRM155R61H104KE14%23"
			(at 0 0 90)
			(layer "B.Fab")
			(hide yes)
			(effects
				(font
					(size 1.27 1.27)
					(thickness 0.15)
				)
				(justify mirror)
			)
		)
		(property "Description" "SMD Multilayer Ceramic Capacitor, 0.1 µF, 50 V, 0402 [1005 Metric], ± 10%, X5R, GRM Series"
			(at 0 0 90)
			(layer "B.Fab")
			(hide yes)
			(effects
				(font
					(size 1.27 1.27)
					(thickness 0.15)
				)
				(justify mirror)
			)
		)
		(property "MPN" "GRM155R61H104KE14D"
			(at 0 0 -90)
			(unlocked yes)
			(layer "B.Fab")
			(hide yes)
			(effects
				(font
					(size 1 1)
					(thickness 0.15)
				)
				(justify mirror)
			)
		)
		(property "Manufacturer" "Murata"
			(at 0 0 -90)
			(unlocked yes)
			(layer "B.Fab")
			(hide yes)
			(effects
				(font
					(size 1 1)
					(thickness 0.15)
				)
				(justify mirror)
			)
		)
		(property "License" "Apache-2.0"
			(at 0 0 -90)
			(unlocked yes)
			(layer "B.Fab")
			(hide yes)
			(effects
				(font
					(size 1 1)
					(thickness 0.15)
				)
				(justify mirror)
			)
		)
		(property "Author" "Antmicro"
			(at 0 0 -90)
			(unlocked yes)
			(layer "B.Fab")
			(hide yes)
			(effects
				(font
					(size 1 1)
					(thickness 0.15)
				)
				(justify mirror)
			)
		)
		(property "Val" "100n"
			(at 0 0 -90)
			(unlocked yes)
			(layer "B.Fab")
			(hide yes)
			(effects
				(font
					(size 1 1)
					(thickness 0.15)
				)
				(justify mirror)
			)
		)
		(property "Voltage" "50V"
			(at 0 0 -90)
			(unlocked yes)
			(layer "B.Fab")
			(hide yes)
			(effects
				(font
					(size 1 1)
					(thickness 0.15)
				)
				(justify mirror)
			)
		)
		(property "Dielectric" "X5R"
			(at 0 0 -90)
			(unlocked yes)
			(layer "B.Fab")
			(hide yes)
			(effects
				(font
					(size 1 1)
					(thickness 0.15)
				)
				(justify mirror)
			)
		)
		(property "Public" "False"
			(at 0 0 -90)
			(unlocked yes)
			(layer "B.Fab")
			(hide yes)
			(effects
				(font
					(size 1 1)
					(thickness 0.15)
				)
				(justify mirror)
			)
		)
		(sheetname "Root")
		(sheetfile "jetson-orin-baseboard-oculink-expansion.kicad_sch")
		(attr smd)
		(fp_rect
			(start -0.925 0.47)
			(end 0.925 -0.47)
			(stroke
				(width 0.05)
				(type default)
			)
			(fill none)
			(layer "B.CrtYd")
		)
		(fp_line
			(start 0.504 -0.248)
			(end 0.504 0.25)
			(stroke
				(width 0.15)
				(type solid)
			)
			(layer "B.Fab")
		)
		(fp_line
			(start -0.494 -0.248)
			(end 0.504 -0.248)
			(stroke
				(width 0.15)
				(type solid)
			)
			(layer "B.Fab")
		)
		(fp_line
			(start 0.504 0.25)
			(end -0.494 0.25)
			(stroke
				(width 0.15)
				(type solid)
			)
			(layer "B.Fab")
		)
		(fp_line
			(start -0.494 0.25)
			(end -0.494 -0.248)
			(stroke
				(width 0.15)
				(type solid)
			)
			(layer "B.Fab")
		)
		(fp_text user "${REFERENCE}"
			(at -0.939 -4.599 90)
			(layer "B.Fab")
			(hide yes)
			(effects
				(font
					(size 0.7 0.7)
					(thickness 0.15)
				)
				(justify right top mirror)
			)
		)
		(fp_text user "Author: Antmicro"
			(at -0.939 -3.399 90)
			(layer "B.Fab")
			(hide yes)
			(effects
				(font
					(size 0.7 0.7)
					(thickness 0.15)
				)
				(justify right top mirror)
			)
		)
		(fp_text user "License: Apache-2.0"
			(at -0.939 -5.799 90)
			(layer "B.Fab")
			(hide yes)
			(effects
				(font
					(size 0.7 0.7)
					(thickness 0.15)
				)
				(justify right top mirror)
			)
		)
		(pad "1" smd roundrect
			(at -0.48 0 90)
			(size 0.59 0.64)
			(layers "B.Cu" "B.Paste" "B.Mask")
			(roundrect_rratio 0.25)
			(net 51 "GND")
			(pintype "passive")
		)
		(pad "2" smd roundrect
			(at 0.48 0 90)
			(size 0.59 0.64)
			(layers "B.Cu" "B.Paste" "B.Mask")
			(roundrect_rratio 0.25)
			(net 23 "+3V3")
			(pintype "passive")
		)
	)
	(footprint "antmicro-footprints:C_0402_1005Metric"
		(layer "B.Cu")
		(at 122.005 114.568251 90)
		(descr "Capacitor SMD 0402")
		(tags "capacitor SMD 0402")
		(property "Reference" "C27"
			(at 1.778251 -0.215 90)
			(layer "B.SilkS")
			(effects
				(font
					(size 0.7 0.7)
					(thickness 0.15)
				)
				(justify right top mirror)
			)
		)
		(property "Value" "C_100n_0402"
			(at -1.022927 -2.155213 90)
			(layer "B.Fab")
			(effects
				(font
					(size 0.7 0.7)
					(thickness 0.15)
				)
				(justify right top mirror)
			)
		)
		(property "Footprint" "antmicro-footprints:C_0402_1005Metric"
			(at 0 0 90)
			(layer "B.Fab")
			(hide yes)
			(effects
				(font
					(size 1.27 1.27)
					(thickness 0.15)
				)
				(justify mirror)
			)
		)
		(property "Datasheet" "https://www.murata.com/products/productdetail?partno=GRM155R61H104KE14%23"
			(at 0 0 90)
			(layer "B.Fab")
			(hide yes)
			(effects
				(font
					(size 1.27 1.27)
					(thickness 0.15)
				)
				(justify mirror)
			)
		)
		(property "Description" "SMD Multilayer Ceramic Capacitor, 0.1 µF, 50 V, 0402 [1005 Metric], ± 10%, X5R, GRM Series"
			(at 0 0 90)
			(layer "B.Fab")
			(hide yes)
			(effects
				(font
					(size 1.27 1.27)
					(thickness 0.15)
				)
				(justify mirror)
			)
		)
		(property "MPN" "GRM155R61H104KE14D"
			(at 0 0 -90)
			(unlocked yes)
			(layer "B.Fab")
			(hide yes)
			(effects
				(font
					(size 1 1)
					(thickness 0.15)
				)
				(justify mirror)
			)
		)
		(property "Manufacturer" "Murata"
			(at 0 0 -90)
			(unlocked yes)
			(layer "B.Fab")
			(hide yes)
			(effects
				(font
					(size 1 1)
					(thickness 0.15)
				)
				(justify mirror)
			)
		)
		(property "License" "Apache-2.0"
			(at 0 0 -90)
			(unlocked yes)
			(layer "B.Fab")
			(hide yes)
			(effects
				(font
					(size 1 1)
					(thickness 0.15)
				)
				(justify mirror)
			)
		)
		(property "Author" "Antmicro"
			(at 0 0 -90)
			(unlocked yes)
			(layer "B.Fab")
			(hide yes)
			(effects
				(font
					(size 1 1)
					(thickness 0.15)
				)
				(justify mirror)
			)
		)
		(property "Val" "100n"
			(at 0 0 -90)
			(unlocked yes)
			(layer "B.Fab")
			(hide yes)
			(effects
				(font
					(size 1 1)
					(thickness 0.15)
				)
				(justify mirror)
			)
		)
		(property "Voltage" "50V"
			(at 0 0 -90)
			(unlocked yes)
			(layer "B.Fab")
			(hide yes)
			(effects
				(font
					(size 1 1)
					(thickness 0.15)
				)
				(justify mirror)
			)
		)
		(property "Dielectric" "X5R"
			(at 0 0 -90)
			(unlocked yes)
			(layer "B.Fab")
			(hide yes)
			(effects
				(font
					(size 1 1)
					(thickness 0.15)
				)
				(justify mirror)
			)
		)
		(property "Public" "False"
			(at 0 0 -90)
			(unlocked yes)
			(layer "B.Fab")
			(hide yes)
			(effects
				(font
					(size 1 1)
					(thickness 0.15)
				)
				(justify mirror)
			)
		)
		(sheetname "Root")
		(sheetfile "jetson-orin-baseboard-oculink-expansion.kicad_sch")
		(attr smd)
		(fp_rect
			(start -0.925 0.47)
			(end 0.925 -0.47)
			(stroke
				(width 0.05)
				(type default)
			)
			(fill none)
			(layer "B.CrtYd")
		)
		(fp_line
			(start 0.504 -0.248)
			(end 0.504 0.25)
			(stroke
				(width 0.15)
				(type solid)
			)
			(layer "B.Fab")
		)
		(fp_line
			(start -0.494 -0.248)
			(end 0.504 -0.248)
			(stroke
				(width 0.15)
				(type solid)
			)
			(layer "B.Fab")
		)
		(fp_line
			(start 0.504 0.25)
			(end -0.494 0.25)
			(stroke
				(width 0.15)
				(type solid)
			)
			(layer "B.Fab")
		)
		(fp_line
			(start -0.494 0.25)
			(end -0.494 -0.248)
			(stroke
				(width 0.15)
				(type solid)
			)
			(layer "B.Fab")
		)
		(fp_text user "License: Apache-2.0"
			(at -0.939 -5.799 90)
			(layer "B.Fab")
			(hide yes)
			(effects
				(font
					(size 0.7 0.7)
					(thickness 0.15)
				)
				(justify right top mirror)
			)
		)
		(fp_text user "Author: Antmicro"
			(at -0.939 -3.399 90)
			(layer "B.Fab")
			(hide yes)
			(effects
				(font
					(size 0.7 0.7)
					(thickness 0.15)
				)
				(justify right top mirror)
			)
		)
		(fp_text user "${REFERENCE}"
			(at -0.939 -4.599 90)
			(layer "B.Fab")
			(hide yes)
			(effects
				(font
					(size 0.7 0.7)
					(thickness 0.15)
				)
				(justify right top mirror)
			)
		)
		(pad "1" smd roundrect
			(at -0.48 0 90)
			(size 0.59 0.64)
			(layers "B.Cu" "B.Paste" "B.Mask")
			(roundrect_rratio 0.25)
			(net 51 "GND")
			(pintype "passive")
		)
		(pad "2" smd roundrect
			(at 0.48 0 90)
			(size 0.59 0.64)
			(layers "B.Cu" "B.Paste" "B.Mask")
			(roundrect_rratio 0.25)
			(net 23 "+3V3")
			(pintype "passive")
		)
	)
	(footprint "antmicro-footprints:R_0402_1005Metric"
		(layer "B.Cu")
		(at 129.804 123.78775 180)
		(descr "Resistor SMD 0402")
		(tags "resistor SMD 0402")
		(property "Reference" "R30"
			(at -3.326 -0.43225 0)
			(layer "B.SilkS")
			(effects
				(font
					(size 0.7 0.7)
					(thickness 0.15)
				)
				(justify left bottom mirror)
			)
		)
		(property "Value" "R_1k_0402"
			(at -1.011843 -1.772047 0)
			(layer "B.Fab")
			(effects
				(font
					(size 0.7 0.7)
					(thickness 0.15)
				)
				(justify left bottom mirror)
			)
		)
		(property "Footprint" "antmicro-footprints:R_0402_1005Metric"
			(at 0 0 0)
			(layer "B.Fab")
			(hide yes)
			(effects
				(font
					(size 1.27 1.27)
					(thickness 0.15)
				)
				(justify mirror)
			)
		)
		(property "Datasheet" "https://www.bourns.com/docs/product-datasheets/cr.pdf"
			(at 0 0 0)
			(layer "B.Fab")
			(hide yes)
			(effects
				(font
					(size 1.27 1.27)
					(thickness 0.15)
				)
				(justify mirror)
			)
		)
		(property "Description" "SMD Chip Resistor, 1 kohm, ± 1%, 63 mW, 0402 [1005 Metric], Thick Film, General Purpose"
			(at 0 0 0)
			(layer "B.Fab")
			(hide yes)
			(effects
				(font
					(size 1.27 1.27)
					(thickness 0.15)
				)
				(justify mirror)
			)
		)
		(property "MPN" "CR0402-FX-1001GLF"
			(at 0 0 0)
			(unlocked yes)
			(layer "B.Fab")
			(hide yes)
			(effects
				(font
					(size 1 1)
					(thickness 0.15)
				)
				(justify mirror)
			)
		)
		(property "Manufacturer" "Bourns"
			(at 0 0 0)
			(unlocked yes)
			(layer "B.Fab")
			(hide yes)
			(effects
				(font
					(size 1 1)
					(thickness 0.15)
				)
				(justify mirror)
			)
		)
		(property "License" "Apache-2.0"
			(at 0 0 0)
			(unlocked yes)
			(layer "B.Fab")
			(hide yes)
			(effects
				(font
					(size 1 1)
					(thickness 0.15)
				)
				(justify mirror)
			)
		)
		(property "Author" "Antmicro"
			(at 0 0 0)
			(unlocked yes)
			(layer "B.Fab")
			(hide yes)
			(effects
				(font
					(size 1 1)
					(thickness 0.15)
				)
				(justify mirror)
			)
		)
		(property "Val" "1k"
			(at 0 0 0)
			(unlocked yes)
			(layer "B.Fab")
			(hide yes)
			(effects
				(font
					(size 1 1)
					(thickness 0.15)
				)
				(justify mirror)
			)
		)
		(property "Tolerance" "1%"
			(at 0 0 0)
			(unlocked yes)
			(layer "B.Fab")
			(hide yes)
			(effects
				(font
					(size 1 1)
					(thickness 0.15)
				)
				(justify mirror)
			)
		)
		(property "Public" "False"
			(at 0 0 0)
			(unlocked yes)
			(layer "B.Fab")
			(hide yes)
			(effects
				(font
					(size 1 1)
					(thickness 0.15)
				)
				(justify mirror)
			)
		)
		(sheetname "Root")
		(sheetfile "jetson-orin-baseboard-oculink-expansion.kicad_sch")
		(attr smd dnp)
		(fp_rect
			(start -0.925 0.47)
			(end 0.925 -0.47)
			(stroke
				(width 0.05)
				(type default)
			)
			(fill none)
			(layer "B.CrtYd")
		)
		(fp_rect
			(start -0.5 0.25)
			(end 0.5 -0.25)
			(stroke
				(width 0.15)
				(type solid)
			)
			(fill none)
			(layer "B.Fab")
		)
		(fp_text user "License: Apache-2.0"
			(at -0.95 -5.169 0)
			(layer "B.Fab")
			(hide yes)
			(effects
				(font
					(size 0.7 0.7)
					(thickness 0.15)
				)
				(justify left bottom mirror)
			)
		)
		(fp_text user "${REFERENCE}"
			(at -0.95 -3.168 0)
			(layer "B.Fab")
			(hide yes)
			(effects
				(font
					(size 0.7 0.7)
					(thickness 0.15)
				)
				(justify left bottom mirror)
			)
		)
		(fp_text user "Author: Antmicro"
			(at -0.95 -4.169 0)
			(layer "B.Fab")
			(hide yes)
			(effects
				(font
					(size 0.7 0.7)
					(thickness 0.15)
				)
				(justify left bottom mirror)
			)
		)
		(pad "1" smd roundrect
			(at -0.48 0 180)
			(size 0.59 0.64)
			(layers "B.Cu" "B.Paste" "B.Mask")
			(roundrect_rratio 0.25)
			(net 51 "GND")
			(pintype "passive")
		)
		(pad "2" smd roundrect
			(at 0.48 0 180)
			(size 0.59 0.64)
			(layers "B.Cu" "B.Paste" "B.Mask")
			(roundrect_rratio 0.25)
			(net 102 "/TX_SW")
			(pintype "passive")
		)
	)
	(footprint "antmicro-footprints:C_0402_1005Metric"
		(layer "B.Cu")
		(at 125.005 116.687251 -90)
		(descr "Capacitor SMD 0402")
		(tags "capacitor SMD 0402")
		(property "Reference" "C12"
			(at 1.782749 -0.435 90)
			(layer "B.SilkS")
			(effects
				(font
					(size 0.7 0.7)
					(thickness 0.15)
				)
				(justify left bottom mirror)
			)
		)
		(property "Value" "C_100n_0402"
			(at -1.022927 -2.155213 90)
			(layer "B.Fab")
			(effects
				(font
					(size 0.7 0.7)
					(thickness 0.15)
				)
				(justify left bottom mirror)
			)
		)
		(property "Footprint" "antmicro-footprints:C_0402_1005Metric"
			(at 0 0 90)
			(layer "B.Fab")
			(hide yes)
			(effects
				(font
					(size 1.27 1.27)
					(thickness 0.15)
				)
				(justify mirror)
			)
		)
		(property "Datasheet" "https://www.murata.com/products/productdetail?partno=GRM155R61H104KE14%23"
			(at 0 0 90)
			(layer "B.Fab")
			(hide yes)
			(effects
				(font
					(size 1.27 1.27)
					(thickness 0.15)
				)
				(justify mirror)
			)
		)
		(property "Description" "SMD Multilayer Ceramic Capacitor, 0.1 µF, 50 V, 0402 [1005 Metric], ± 10%, X5R, GRM Series"
			(at 0 0 90)
			(layer "B.Fab")
			(hide yes)
			(effects
				(font
					(size 1.27 1.27)
					(thickness 0.15)
				)
				(justify mirror)
			)
		)
		(property "MPN" "GRM155R61H104KE14D"
			(at 0 0 90)
			(unlocked yes)
			(layer "B.Fab")
			(hide yes)
			(effects
				(font
					(size 1 1)
					(thickness 0.15)
				)
				(justify mirror)
			)
		)
		(property "Manufacturer" "Murata"
			(at 0 0 90)
			(unlocked yes)
			(layer "B.Fab")
			(hide yes)
			(effects
				(font
					(size 1 1)
					(thickness 0.15)
				)
				(justify mirror)
			)
		)
		(property "License" "Apache-2.0"
			(at 0 0 90)
			(unlocked yes)
			(layer "B.Fab")
			(hide yes)
			(effects
				(font
					(size 1 1)
					(thickness 0.15)
				)
				(justify mirror)
			)
		)
		(property "Author" "Antmicro"
			(at 0 0 90)
			(unlocked yes)
			(layer "B.Fab")
			(hide yes)
			(effects
				(font
					(size 1 1)
					(thickness 0.15)
				)
				(justify mirror)
			)
		)
		(property "Val" "100n"
			(at 0 0 90)
			(unlocked yes)
			(layer "B.Fab")
			(hide yes)
			(effects
				(font
					(size 1 1)
					(thickness 0.15)
				)
				(justify mirror)
			)
		)
		(property "Voltage" "50V"
			(at 0 0 90)
			(unlocked yes)
			(layer "B.Fab")
			(hide yes)
			(effects
				(font
					(size 1 1)
					(thickness 0.15)
				)
				(justify mirror)
			)
		)
		(property "Dielectric" "X5R"
			(at 0 0 90)
			(unlocked yes)
			(layer "B.Fab")
			(hide yes)
			(effects
				(font
					(size 1 1)
					(thickness 0.15)
				)
				(justify mirror)
			)
		)
		(property "Public" "False"
			(at 0 0 90)
			(unlocked yes)
			(layer "B.Fab")
			(hide yes)
			(effects
				(font
					(size 1 1)
					(thickness 0.15)
				)
				(justify mirror)
			)
		)
		(sheetname "Root")
		(sheetfile "jetson-orin-baseboard-oculink-expansion.kicad_sch")
		(attr smd)
		(fp_rect
			(start -0.925 0.47)
			(end 0.925 -0.47)
			(stroke
				(width 0.05)
				(type default)
			)
			(fill none)
			(layer "B.CrtYd")
		)
		(fp_line
			(start -0.494 0.25)
			(end -0.494 -0.248)
			(stroke
				(width 0.15)
				(type solid)
			)
			(layer "B.Fab")
		)
		(fp_line
			(start 0.504 0.25)
			(end -0.494 0.25)
			(stroke
				(width 0.15)
				(type solid)
			)
			(layer "B.Fab")
		)
		(fp_line
			(start -0.494 -0.248)
			(end 0.504 -0.248)
			(stroke
				(width 0.15)
				(type solid)
			)
			(layer "B.Fab")
		)
		(fp_line
			(start 0.504 -0.248)
			(end 0.504 0.25)
			(stroke
				(width 0.15)
				(type solid)
			)
			(layer "B.Fab")
		)
		(fp_text user "${REFERENCE}"
			(at -0.939 -4.599 90)
			(layer "B.Fab")
			(hide yes)
			(effects
				(font
					(size 0.7 0.7)
					(thickness 0.15)
				)
				(justify left bottom mirror)
			)
		)
		(fp_text user "Author: Antmicro"
			(at -0.939 -3.399 90)
			(layer "B.Fab")
			(hide yes)
			(effects
				(font
					(size 0.7 0.7)
					(thickness 0.15)
				)
				(justify left bottom mirror)
			)
		)
		(fp_text user "License: Apache-2.0"
			(at -0.939 -5.799 90)
			(layer "B.Fab")
			(hide yes)
			(effects
				(font
					(size 0.7 0.7)
					(thickness 0.15)
				)
				(justify left bottom mirror)
			)
		)
		(pad "1" smd roundrect
			(at -0.48 0 270)
			(size 0.59 0.64)
			(layers "B.Cu" "B.Paste" "B.Mask")
			(roundrect_rratio 0.25)
			(net 51 "GND")
			(pintype "passive")
		)
		(pad "2" smd roundrect
			(at 0.48 0 270)
			(size 0.59 0.64)
			(layers "B.Cu" "B.Paste" "B.Mask")
			(roundrect_rratio 0.25)
			(net 23 "+3V3")
			(pintype "passive")
		)
	)
)
